(kicad_pcb
	(version 20260206)
	(generator "pcbnew")
	(generator_version "10.0")
	(general
		(thickness 1.6)
		(legacy_teardrops no)
	)
	(paper "A4")
	(title_block
		(title "12092022_DA0F0TMDCD0_F0T_Management_Board_D_brd_V3_OCP.brd")
		(comment 1 "Grand Teton / footprints 1-6 of 1440")
	)
	(layers
		(0 "F.Cu" signal "TOP")
		(4 "In1.Cu" signal "GND")
		(6 "In2.Cu" signal "IN1")
		(8 "In3.Cu" signal "GND1")
		(10 "In4.Cu" signal "IN2")
		(12 "In5.Cu" signal "VCC")
		(14 "In6.Cu" signal "VCC1")
		(16 "In7.Cu" signal "IN3")
		(18 "In8.Cu" signal "GND2")
		(20 "In9.Cu" signal "IN4")
		(22 "In10.Cu" signal "GND3")
		(2 "B.Cu" signal "BOTTOM")
		(9 "F.Adhes" user "F.Adhesive")
		(11 "B.Adhes" user "B.Adhesive")
		(13 "F.Paste" user "Package Geometry/Pastemask Top")
		(15 "B.Paste" user "Package Geometry/Pastemask Bottom")
		(5 "F.SilkS" user "Ref Des/Silkscreen Top")
		(7 "B.SilkS" user "Ref Des/Silkscreen Bottom")
		(1 "F.Mask" user "Board Geometry/Soldermask Top")
		(3 "B.Mask" user "Board Geometry/Soldermask Bottom")
		(17 "Dwgs.User" user "User.Drawings")
		(19 "Cmts.User" user "User.Comments")
		(21 "Eco1.User" user "User.Eco1")
		(23 "Eco2.User" user "User.Eco2")
		(25 "Edge.Cuts" user "Board Geometry/Outline")
		(27 "Margin" user)
		(31 "F.CrtYd" user "Package Geometry/Place Bound Top")
		(29 "B.CrtYd" user "Package Geometry/Place Bound Bottom")
		(35 "F.Fab" user "Ref Des/Assembly Top")
		(33 "B.Fab" user "Ref Des/Assembly Bottom")
	)
	(footprint ""
		(layer "F.Cu")
		(at 12.319 -93.472 180)
		(property "Reference" "R531"
			(at 0 0 180)
			(layer "F.SilkS")
			(hide yes)
			(effects
				(font
					(size 1.27 1.27)
				)
			)
		)
		(property "Value" ""
			(at 0 0 180)
			(layer "F.Fab")
			(effects
				(font
					(size 1.27 1.27)
				)
			)
		)
		(duplicate_pad_numbers_are_jumpers no)
		(fp_line
			(start 0.7874 0.4064)
			(end -0.7874 0.4064)
			(stroke
				(width 0.1524)
				(type default)
			)
			(layer "F.SilkS")
		)
		(fp_line
			(start 0.7874 -0.4064)
			(end 0.7874 0.4064)
			(stroke
				(width 0.1524)
				(type default)
			)
			(layer "F.SilkS")
		)
		(fp_line
			(start -0.7874 0.4064)
			(end -0.7874 -0.4064)
			(stroke
				(width 0.1524)
				(type default)
			)
			(layer "F.SilkS")
		)
		(fp_line
			(start -0.7874 -0.4064)
			(end 0.7874 -0.4064)
			(stroke
				(width 0.1524)
				(type default)
			)
			(layer "F.SilkS")
		)
		(fp_line
			(start 0.67945 0.3048)
			(end 0.120396 0.3048)
			(stroke
				(width 0.1)
				(type default)
			)
			(layer "F.Fab")
		)
		(fp_line
			(start 0.67945 -0.3048)
			(end 0.67945 0.3048)
			(stroke
				(width 0.1)
				(type default)
			)
			(layer "F.Fab")
		)
		(fp_line
			(start 0.12065 -0.2794)
			(end 0.12065 -0.3048)
			(stroke
				(width 0.1)
				(type default)
			)
			(layer "F.Fab")
		)
		(fp_line
			(start 0.12065 -0.3048)
			(end 0.67945 -0.3048)
			(stroke
				(width 0.1)
				(type default)
			)
			(layer "F.Fab")
		)
		(fp_line
			(start 0.120396 0.3048)
			(end 0.120396 0.2794)
			(stroke
				(width 0.1)
				(type default)
			)
			(layer "F.Fab")
		)
		(fp_line
			(start 0.120396 0.2794)
			(end -0.12065 0.2794)
			(stroke
				(width 0.1)
				(type default)
			)
			(layer "F.Fab")
		)
		(fp_line
			(start -0.12065 0.3048)
			(end -0.67945 0.3048)
			(stroke
				(width 0.1)
				(type default)
			)
			(layer "F.Fab")
		)
		(fp_line
			(start -0.12065 0.2794)
			(end -0.12065 0.3048)
			(stroke
				(width 0.1)
				(type default)
			)
			(layer "F.Fab")
		)
		(fp_line
			(start -0.12065 -0.2794)
			(end 0.12065 -0.2794)
			(stroke
				(width 0.1)
				(type default)
			)
			(layer "F.Fab")
		)
		(fp_line
			(start -0.12065 -0.305054)
			(end -0.12065 -0.2794)
			(stroke
				(width 0.1)
				(type default)
			)
			(layer "F.Fab")
		)
		(fp_line
			(start -0.67945 0.3048)
			(end -0.67945 -0.305054)
			(stroke
				(width 0.1)
				(type default)
			)
			(layer "F.Fab")
		)
		(fp_line
			(start -0.67945 -0.305054)
			(end -0.12065 -0.305054)
			(stroke
				(width 0.1)
				(type default)
			)
			(layer "F.Fab")
		)
		(pad "1" smd circle
			(at -0.40005 0 180)
			(size 0 0)
			(layers "F.Cu" "F.Mask" "F.Paste")
			(net "BMC_CPLD_GPIO_8_R2")
		)
		(pad "2" smd circle
			(at 0.40005 0 180)
			(size 0 0)
			(layers "F.Cu" "F.Mask" "F.Paste")
			(net "BMC_CPLD_GPIO_8")
		)
	)
	(footprint ""
		(layer "F.Cu")
		(at 13.31976 -64.54394 90)
		(property "Reference" "PR534"
			(at 0 0 90)
			(layer "F.SilkS")
			(hide yes)
			(effects
				(font
					(size 1.27 1.27)
				)
			)
		)
		(property "Value" ""
			(at 0 0 90)
			(layer "F.Fab")
			(effects
				(font
					(size 1.27 1.27)
				)
			)
		)
		(duplicate_pad_numbers_are_jumpers no)
		(fp_line
			(start 0.7874 -0.4064)
			(end 0.7874 0.4064)
			(stroke
				(width 0.1524)
				(type default)
			)
			(layer "F.SilkS")
		)
		(fp_line
			(start -0.7874 -0.4064)
			(end 0.7874 -0.4064)
			(stroke
				(width 0.1524)
				(type default)
			)
			(layer "F.SilkS")
		)
		(fp_line
			(start 0.7874 0.4064)
			(end -0.7874 0.4064)
			(stroke
				(width 0.1524)
				(type default)
			)
			(layer "F.SilkS")
		)
		(fp_line
			(start -0.7874 0.4064)
			(end -0.7874 -0.4064)
			(stroke
				(width 0.1524)
				(type default)
			)
			(layer "F.SilkS")
		)
		(fp_line
			(start -0.12065 -0.305054)
			(end -0.12065 -0.2794)
			(stroke
				(width 0.1)
				(type default)
			)
			(layer "F.Fab")
		)
		(fp_line
			(start -0.67945 -0.305054)
			(end -0.12065 -0.305054)
			(stroke
				(width 0.1)
				(type default)
			)
			(layer "F.Fab")
		)
		(fp_line
			(start 0.67945 -0.3048)
			(end 0.67945 0.3048)
			(stroke
				(width 0.1)
				(type default)
			)
			(layer "F.Fab")
		)
		(fp_line
			(start 0.12065 -0.3048)
			(end 0.67945 -0.3048)
			(stroke
				(width 0.1)
				(type default)
			)
			(layer "F.Fab")
		)
		(fp_line
			(start 0.12065 -0.2794)
			(end 0.12065 -0.3048)
			(stroke
				(width 0.1)
				(type default)
			)
			(layer "F.Fab")
		)
		(fp_line
			(start -0.12065 -0.2794)
			(end 0.12065 -0.2794)
			(stroke
				(width 0.1)
				(type default)
			)
			(layer "F.Fab")
		)
		(fp_line
			(start 0.120396 0.2794)
			(end -0.12065 0.2794)
			(stroke
				(width 0.1)
				(type default)
			)
			(layer "F.Fab")
		)
		(fp_line
			(start -0.12065 0.2794)
			(end -0.12065 0.3048)
			(stroke
				(width 0.1)
				(type default)
			)
			(layer "F.Fab")
		)
		(fp_line
			(start 0.67945 0.3048)
			(end 0.120396 0.3048)
			(stroke
				(width 0.1)
				(type default)
			)
			(layer "F.Fab")
		)
		(fp_line
			(start 0.120396 0.3048)
			(end 0.120396 0.2794)
			(stroke
				(width 0.1)
				(type default)
			)
			(layer "F.Fab")
		)
		(fp_line
			(start -0.12065 0.3048)
			(end -0.67945 0.3048)
			(stroke
				(width 0.1)
				(type default)
			)
			(layer "F.Fab")
		)
		(fp_line
			(start -0.67945 0.3048)
			(end -0.67945 -0.305054)
			(stroke
				(width 0.1)
				(type default)
			)
			(layer "F.Fab")
		)
		(pad "1" smd circle
			(at -0.40005 0 90)
			(size 0 0)
			(layers "F.Cu" "F.Mask" "F.Paste")
			(net "P3V3_AUX_FB_RC")
		)
		(pad "2" smd circle
			(at 0.40005 0 90)
			(size 0 0)
			(layers "F.Cu" "F.Mask" "F.Paste")
			(net "P3V3_AUX")
		)
	)
	(footprint ""
		(layer "F.Cu")
		(at 46.5709 -66.23812 90)
		(property "Reference" "R26"
			(at 0 0 90)
			(layer "F.SilkS")
			(hide yes)
			(effects
				(font
					(size 1.27 1.27)
				)
			)
		)
		(property "Value" ""
			(at 0 0 90)
			(layer "F.Fab")
			(effects
				(font
					(size 1.27 1.27)
				)
			)
		)
		(duplicate_pad_numbers_are_jumpers no)
		(fp_line
			(start 0.7874 -0.4064)
			(end 0.7874 0.4064)
			(stroke
				(width 0.1524)
				(type default)
			)
			(layer "F.SilkS")
		)
		(fp_line
			(start -0.7874 -0.4064)
			(end 0.7874 -0.4064)
			(stroke
				(width 0.1524)
				(type default)
			)
			(layer "F.SilkS")
		)
		(fp_line
			(start 0.7874 0.4064)
			(end -0.7874 0.4064)
			(stroke
				(width 0.1524)
				(type default)
			)
			(layer "F.SilkS")
		)
		(fp_line
			(start -0.7874 0.4064)
			(end -0.7874 -0.4064)
			(stroke
				(width 0.1524)
				(type default)
			)
			(layer "F.SilkS")
		)
		(fp_line
			(start -0.12065 -0.305054)
			(end -0.12065 -0.2794)
			(stroke
				(width 0.1)
				(type default)
			)
			(layer "F.Fab")
		)
		(fp_line
			(start -0.67945 -0.305054)
			(end -0.12065 -0.305054)
			(stroke
				(width 0.1)
				(type default)
			)
			(layer "F.Fab")
		)
		(fp_line
			(start 0.67945 -0.3048)
			(end 0.67945 0.3048)
			(stroke
				(width 0.1)
				(type default)
			)
			(layer "F.Fab")
		)
		(fp_line
			(start 0.12065 -0.3048)
			(end 0.67945 -0.3048)
			(stroke
				(width 0.1)
				(type default)
			)
			(layer "F.Fab")
		)
		(fp_line
			(start 0.12065 -0.2794)
			(end 0.12065 -0.3048)
			(stroke
				(width 0.1)
				(type default)
			)
			(layer "F.Fab")
		)
		(fp_line
			(start -0.12065 -0.2794)
			(end 0.12065 -0.2794)
			(stroke
				(width 0.1)
				(type default)
			)
			(layer "F.Fab")
		)
		(fp_line
			(start 0.120396 0.2794)
			(end -0.12065 0.2794)
			(stroke
				(width 0.1)
				(type default)
			)
			(layer "F.Fab")
		)
		(fp_line
			(start -0.12065 0.2794)
			(end -0.12065 0.3048)
			(stroke
				(width 0.1)
				(type default)
			)
			(layer "F.Fab")
		)
		(fp_line
			(start 0.67945 0.3048)
			(end 0.120396 0.3048)
			(stroke
				(width 0.1)
				(type default)
			)
			(layer "F.Fab")
		)
		(fp_line
			(start 0.120396 0.3048)
			(end 0.120396 0.2794)
			(stroke
				(width 0.1)
				(type default)
			)
			(layer "F.Fab")
		)
		(fp_line
			(start -0.12065 0.3048)
			(end -0.67945 0.3048)
			(stroke
				(width 0.1)
				(type default)
			)
			(layer "F.Fab")
		)
		(fp_line
			(start -0.67945 0.3048)
			(end -0.67945 -0.305054)
			(stroke
				(width 0.1)
				(type default)
			)
			(layer "F.Fab")
		)
		(pad "1" smd circle
			(at -0.40005 0 90)
			(size 0 0)
			(layers "F.Cu" "F.Mask" "F.Paste")
			(net "V_DACR_R")
		)
		(pad "2" smd circle
			(at 0.40005 0 90)
			(size 0 0)
			(layers "F.Cu" "F.Mask" "F.Paste")
			(net "V_DACR")
		)
	)
	(footprint ""
		(layer "F.Cu")
		(at 63.960502 -68.174362)
		(property "Reference" "C224"
			(at 0 0 0)
			(layer "F.SilkS")
			(hide yes)
			(effects
				(font
					(size 1.27 1.27)
				)
			)
		)
		(property "Value" ""
			(at 0 0 0)
			(layer "F.Fab")
			(effects
				(font
					(size 1.27 1.27)
				)
			)
		)
		(duplicate_pad_numbers_are_jumpers no)
		(fp_line
			(start -0.7874 -0.4064)
			(end 0.7874 -0.4064)
			(stroke
				(width 0.1524)
				(type default)
			)
			(layer "F.SilkS")
		)
		(fp_line
			(start -0.7874 0.4064)
			(end -0.7874 -0.4064)
			(stroke
				(width 0.1524)
				(type default)
			)
			(layer "F.SilkS")
		)
		(fp_line
			(start 0.7874 -0.4064)
			(end 0.7874 0.4064)
			(stroke
				(width 0.1524)
				(type default)
			)
			(layer "F.SilkS")
		)
		(fp_line
			(start 0.7874 0.4064)
			(end -0.7874 0.4064)
			(stroke
				(width 0.1524)
				(type default)
			)
			(layer "F.SilkS")
		)
		(fp_line
			(start -0.67945 -0.305054)
			(end -0.12065 -0.305054)
			(stroke
				(width 0.1)
				(type default)
			)
			(layer "F.Fab")
		)
		(fp_line
			(start -0.67945 0.3048)
			(end -0.67945 -0.305054)
			(stroke
				(width 0.1)
				(type default)
			)
			(layer "F.Fab")
		)
		(fp_line
			(start -0.12065 -0.305054)
			(end -0.12065 -0.2794)
			(stroke
				(width 0.1)
				(type default)
			)
			(layer "F.Fab")
		)
		(fp_line
			(start -0.12065 -0.2794)
			(end 0.12065 -0.2794)
			(stroke
				(width 0.1)
				(type default)
			)
			(layer "F.Fab")
		)
		(fp_line
			(start -0.12065 0.2794)
			(end -0.12065 0.3048)
			(stroke
				(width 0.1)
				(type default)
			)
			(layer "F.Fab")
		)
		(fp_line
			(start -0.12065 0.3048)
			(end -0.67945 0.3048)
			(stroke
				(width 0.1)
				(type default)
			)
			(layer "F.Fab")
		)
		(fp_line
			(start 0.120396 0.2794)
			(end -0.12065 0.2794)
			(stroke
				(width 0.1)
				(type default)
			)
			(layer "F.Fab")
		)
		(fp_line
			(start 0.120396 0.3048)
			(end 0.120396 0.2794)
			(stroke
				(width 0.1)
				(type default)
			)
			(layer "F.Fab")
		)
		(fp_line
			(start 0.12065 -0.3048)
			(end 0.67945 -0.3048)
			(stroke
				(width 0.1)
				(type default)
			)
			(layer "F.Fab")
		)
		(fp_line
			(start 0.12065 -0.2794)
			(end 0.12065 -0.3048)
			(stroke
				(width 0.1)
				(type default)
			)
			(layer "F.Fab")
		)
		(fp_line
			(start 0.67945 -0.3048)
			(end 0.67945 0.3048)
			(stroke
				(width 0.1)
				(type default)
			)
			(layer "F.Fab")
		)
		(fp_line
			(start 0.67945 0.3048)
			(end 0.120396 0.3048)
			(stroke
				(width 0.1)
				(type default)
			)
			(layer "F.Fab")
		)
		(pad "1" smd circle
			(at -0.40005 0)
			(size 0 0)
			(layers "F.Cu" "F.Mask" "F.Paste")
			(net "PGPPA_BMC_AUX")
		)
		(pad "2" smd circle
			(at 0.40005 0)
			(size 0 0)
			(layers "F.Cu" "F.Mask" "F.Paste")
			(net "GND")
		)
	)
	(footprint ""
		(layer "F.Cu")
		(at 42.932604 -87.679784 90)
		(property "Reference" "R490"
			(at 0 0 90)
			(layer "F.SilkS")
			(hide yes)
			(effects
				(font
					(size 1.27 1.27)
				)
			)
		)
		(property "Value" ""
			(at 0 0 90)
			(layer "F.Fab")
			(effects
				(font
					(size 1.27 1.27)
				)
			)
		)
		(duplicate_pad_numbers_are_jumpers no)
		(fp_line
			(start 0.7874 -0.4064)
			(end 0.7874 0.4064)
			(stroke
				(width 0.1524)
				(type default)
			)
			(layer "F.SilkS")
		)
		(fp_line
			(start -0.7874 -0.4064)
			(end 0.7874 -0.4064)
			(stroke
				(width 0.1524)
				(type default)
			)
			(layer "F.SilkS")
		)
		(fp_line
			(start 0.7874 0.4064)
			(end -0.7874 0.4064)
			(stroke
				(width 0.1524)
				(type default)
			)
			(layer "F.SilkS")
		)
		(fp_line
			(start -0.7874 0.4064)
			(end -0.7874 -0.4064)
			(stroke
				(width 0.1524)
				(type default)
			)
			(layer "F.SilkS")
		)
		(fp_line
			(start -0.12065 -0.305054)
			(end -0.12065 -0.2794)
			(stroke
				(width 0.1)
				(type default)
			)
			(layer "F.Fab")
		)
		(fp_line
			(start -0.67945 -0.305054)
			(end -0.12065 -0.305054)
			(stroke
				(width 0.1)
				(type default)
			)
			(layer "F.Fab")
		)
		(fp_line
			(start 0.67945 -0.3048)
			(end 0.67945 0.3048)
			(stroke
				(width 0.1)
				(type default)
			)
			(layer "F.Fab")
		)
		(fp_line
			(start 0.12065 -0.3048)
			(end 0.67945 -0.3048)
			(stroke
				(width 0.1)
				(type default)
			)
			(layer "F.Fab")
		)
		(fp_line
			(start 0.12065 -0.2794)
			(end 0.12065 -0.3048)
			(stroke
				(width 0.1)
				(type default)
			)
			(layer "F.Fab")
		)
		(fp_line
			(start -0.12065 -0.2794)
			(end 0.12065 -0.2794)
			(stroke
				(width 0.1)
				(type default)
			)
			(layer "F.Fab")
		)
		(fp_line
			(start 0.120396 0.2794)
			(end -0.12065 0.2794)
			(stroke
				(width 0.1)
				(type default)
			)
			(layer "F.Fab")
		)
		(fp_line
			(start -0.12065 0.2794)
			(end -0.12065 0.3048)
			(stroke
				(width 0.1)
				(type default)
			)
			(layer "F.Fab")
		)
		(fp_line
			(start 0.67945 0.3048)
			(end 0.120396 0.3048)
			(stroke
				(width 0.1)
				(type default)
			)
			(layer "F.Fab")
		)
		(fp_line
			(start 0.120396 0.3048)
			(end 0.120396 0.2794)
			(stroke
				(width 0.1)
				(type default)
			)
			(layer "F.Fab")
		)
		(fp_line
			(start -0.12065 0.3048)
			(end -0.67945 0.3048)
			(stroke
				(width 0.1)
				(type default)
			)
			(layer "F.Fab")
		)
		(fp_line
			(start -0.67945 0.3048)
			(end -0.67945 -0.305054)
			(stroke
				(width 0.1)
				(type default)
			)
			(layer "F.Fab")
		)
		(pad "1" smd circle
			(at -0.40005 0 90)
			(size 0 0)
			(layers "F.Cu" "F.Mask" "F.Paste")
			(net "P3V3_AUX")
		)
		(pad "2" smd circle
			(at 0.40005 0 90)
			(size 0 0)
			(layers "F.Cu" "F.Mask" "F.Paste")
			(net "SPI_PCH_CS0_FLASH_R1_N")
		)
	)
	(footprint ""
		(layer "F.Cu")
		(at 39.8272 -75.438)
		(property "Reference" "R552"
			(at 0 0 0)
			(layer "F.SilkS")
			(hide yes)
			(effects
				(font
					(size 1.27 1.27)
				)
			)
		)
		(property "Value" ""
			(at 0 0 0)
			(layer "F.Fab")
			(effects
				(font
					(size 1.27 1.27)
				)
			)
		)
		(duplicate_pad_numbers_are_jumpers no)
		(fp_line
			(start -0.7874 -0.4064)
			(end 0.7874 -0.4064)
			(stroke
				(width 0.1524)
				(type default)
			)
			(layer "F.SilkS")
		)
		(fp_line
			(start -0.7874 0.4064)
			(end -0.7874 -0.4064)
			(stroke
				(width 0.1524)
				(type default)
			)
			(layer "F.SilkS")
		)
		(fp_line
			(start 0.7874 -0.4064)
			(end 0.7874 0.4064)
			(stroke
				(width 0.1524)
				(type default)
			)
			(layer "F.SilkS")
		)
		(fp_line
			(start 0.7874 0.4064)
			(end -0.7874 0.4064)
			(stroke
				(width 0.1524)
				(type default)
			)
			(layer "F.SilkS")
		)
		(fp_line
			(start -0.67945 -0.305054)
			(end -0.12065 -0.305054)
			(stroke
				(width 0.1)
				(type default)
			)
			(layer "F.Fab")
		)
		(fp_line
			(start -0.67945 0.3048)
			(end -0.67945 -0.305054)
			(stroke
				(width 0.1)
				(type default)
			)
			(layer "F.Fab")
		)
		(fp_line
			(start -0.12065 -0.305054)
			(end -0.12065 -0.2794)
			(stroke
				(width 0.1)
				(type default)
			)
			(layer "F.Fab")
		)
		(fp_line
			(start -0.12065 -0.2794)
			(end 0.12065 -0.2794)
			(stroke
				(width 0.1)
				(type default)
			)
			(layer "F.Fab")
		)
		(fp_line
			(start -0.12065 0.2794)
			(end -0.12065 0.3048)
			(stroke
				(width 0.1)
				(type default)
			)
			(layer "F.Fab")
		)
		(fp_line
			(start -0.12065 0.3048)
			(end -0.67945 0.3048)
			(stroke
				(width 0.1)
				(type default)
			)
			(layer "F.Fab")
		)
		(fp_line
			(start 0.120396 0.2794)
			(end -0.12065 0.2794)
			(stroke
				(width 0.1)
				(type default)
			)
			(layer "F.Fab")
		)
		(fp_line
			(start 0.120396 0.3048)
			(end 0.120396 0.2794)
			(stroke
				(width 0.1)
				(type default)
			)
			(layer "F.Fab")
		)
		(fp_line
			(start 0.12065 -0.3048)
			(end 0.67945 -0.3048)
			(stroke
				(width 0.1)
				(type default)
			)
			(layer "F.Fab")
		)
		(fp_line
			(start 0.12065 -0.2794)
			(end 0.12065 -0.3048)
			(stroke
				(width 0.1)
				(type default)
			)
			(layer "F.Fab")
		)
		(fp_line
			(start 0.67945 -0.3048)
			(end 0.67945 0.3048)
			(stroke
				(width 0.1)
				(type default)
			)
			(layer "F.Fab")
		)
		(fp_line
			(start 0.67945 0.3048)
			(end 0.120396 0.3048)
			(stroke
				(width 0.1)
				(type default)
			)
			(layer "F.Fab")
		)
		(pad "1" smd circle
			(at -0.40005 0)
			(size 0 0)
			(layers "F.Cu" "F.Mask" "F.Paste")
			(net "SPI_BMC_IO1_FLASH_R")
		)
		(pad "2" smd circle
			(at 0.40005 0)
			(size 0 0)
			(layers "F.Cu" "F.Mask" "F.Paste")
			(net "SPI_BMC_BOOT_MISO")
		)
	)
)
